# BASEBOARD_FAB2 (Tioga Pass) — schematic netlist excerpt (pin names and nets, part order shuffled) for the footprints in the layout excerpt that follows; sources: Cadence DE-HDL packaged netlist, KiCad conversion of Wiwynn_Tioga_Pass_MB.brd

U10W1  TTL1G07_A  74LVC1G07 IC  pkg SOP  page 251 : A = PUMP_PWM_OUT ; Y = PUMP_PWM_OUT_BUF
L7F1  INDUCTOR  0.47UH 1% IND  pkg SM  page 231 : INA = VR_PVPP_ABC_PHASE ; INB = PVPP_ABC
R4B12  RES  0.002 1% CHIP  pkg 1206  page 197 : A = P12V_STBY ; B = P12V_NVDIMM_DEF

(kicad_pcb
	(version 20260206)
	(generator "pcbnew")
	(generator_version "10.0")
	(general
		(thickness 1.6)
		(legacy_teardrops no)
	)
	(paper "A4")
	(title_block
		(title "Wiwynn_Tioga_Pass_MB.brd")
		(comment 1 "Tioga Pass / footprints 216-218 of 4770")
	)
	(layers
		(0 "F.Cu" signal "TOP")
		(4 "In1.Cu" signal "L2GND")
		(6 "In2.Cu" signal "L3")
		(8 "In3.Cu" signal "L4GND")
		(10 "In4.Cu" signal "L5")
		(12 "In5.Cu" signal "L6GND")
		(14 "In6.Cu" signal "L7VCC")
		(16 "In7.Cu" signal "L8VCC")
		(18 "In8.Cu" signal "L9GND")
		(20 "In9.Cu" signal "L10")
		(22 "In10.Cu" signal "L11GND")
		(24 "In11.Cu" signal "L12")
		(26 "In12.Cu" signal "L13GND")
		(2 "B.Cu" signal "BOTTOM")
		(9 "F.Adhes" user "F.Adhesive")
		(11 "B.Adhes" user "B.Adhesive")
		(13 "F.Paste" user "Package Geometry/Pastemask Top")
		(15 "B.Paste" user "Package Geometry/Pastemask Bottom")
		(5 "F.SilkS" user "Ref Des/Silkscreen Top")
		(7 "B.SilkS" user "Ref Des/Silkscreen Bottom")
		(1 "F.Mask" user "Board Geometry/Soldermask Top")
		(3 "B.Mask" user "Board Geometry/Soldermask Bottom")
		(17 "Dwgs.User" user "User.Drawings")
		(19 "Cmts.User" user "User.Comments")
		(21 "Eco1.User" user "User.Eco1")
		(23 "Eco2.User" user "User.Eco2")
		(25 "Edge.Cuts" user "Board Geometry/Outline")
		(27 "Margin" user)
		(31 "F.CrtYd" user "Package Geometry/Place Bound Top")
		(29 "B.CrtYd" user "Package Geometry/Place Bound Bottom")
		(35 "F.Fab" user "Ref Des/Assembly Top")
		(33 "B.Fab" user "Ref Des/Assembly Bottom")
	)
	(footprint ""
		(layer "F.Cu")
		(at 192.685162 -125.774958 180)
		(property "Reference" "R4B12"
			(at 0 0 180)
			(layer "F.SilkS")
			(hide yes)
			(effects
				(font
					(size 1.27 1.27)
				)
			)
		)
		(property "Value" ""
			(at 0 0 180)
			(layer "F.Fab")
			(effects
				(font
					(size 1.27 1.27)
				)
			)
		)
		(duplicate_pad_numbers_are_jumpers no)
		(fp_line
			(start 0.9017 1.952498)
			(end 0.9017 0.853948)
			(stroke
				(width 0.1524)
				(type default)
			)
			(layer "F.SilkS")
		)
		(fp_line
			(start -0.9017 1.951736)
			(end -0.9017 0.823468)
			(stroke
				(width 0.1524)
				(type default)
			)
			(layer "F.SilkS")
		)
		(fp_rect
			(start -0.9017 3.0988)
			(end 0.9017 -0.3048)
			(stroke
				(width 0)
				(type default)
			)
			(fill no)
			(layer "F.CrtYd")
		)
		(fp_line
			(start 0.9017 3.0988)
			(end 0.9017 -0.3048)
			(stroke
				(width 0.1)
				(type default)
			)
			(layer "F.Fab")
		)
		(fp_line
			(start 0.9017 -0.3048)
			(end -0.9017 -0.3048)
			(stroke
				(width 0.1)
				(type default)
			)
			(layer "F.Fab")
		)
		(fp_line
			(start -0.9017 3.0988)
			(end 0.9017 3.0988)
			(stroke
				(width 0.1)
				(type default)
			)
			(layer "F.Fab")
		)
		(fp_line
			(start -0.9017 -0.3048)
			(end -0.9017 3.0988)
			(stroke
				(width 0.1)
				(type default)
			)
			(layer "F.Fab")
		)
		(pad "1" smd rect
			(at 0 0 180)
			(size 1.524 1.016)
			(layers "F.Cu" "F.Mask" "F.Paste")
			(net "P12V_STBY")
		)
		(pad "2" smd rect
			(at 0 2.794 180)
			(size 1.524 1.016)
			(layers "F.Cu" "F.Mask" "F.Paste")
			(net "P12V_NVDIMM_DEF")
		)
		(zone
			(layer "F.Cu")
			(hatch none 0.5)
			(connect_pads
				(clearance 0)
			)
			(min_thickness 0.25)
			(keepout
				(tracks allowed)
				(vias not_allowed)
				(pads allowed)
				(copperpour not_allowed)
				(footprints allowed)
			)
			(placement
				(enabled no)
				(sheetname "")
			)
			(fill
				(thermal_gap 0.5)
				(thermal_bridge_width 0.5)
				(island_removal_mode 0)
			)
			(polygon
				(pts
					(xy 193.447162 -128.060958) (xy 191.923162 -128.060958) (xy 191.923162 -126.282958) (xy 193.447162 -126.282958)
				)
			)
		)
	)
	(footprint ""
		(layer "F.Cu")
		(at 433.084986 -21.505672 -90)
		(property "Reference" "U10W1"
			(at -0.14986 2.621788 270)
			(unlocked yes)
			(layer "F.SilkS")
			(effects
				(font
					(size 1.27 0.964946)
					(thickness 0.000001)
				)
				(justify left)
			)
		)
		(property "Value" ""
			(at 0 0 270)
			(layer "F.Fab")
			(effects
				(font
					(size 1.27 1.27)
				)
			)
		)
		(duplicate_pad_numbers_are_jumpers no)
		(fp_circle
			(center -0.4699 -0.8382)
			(end -0.4699 -0.9652)
			(stroke
				(width 0.254)
				(type default)
			)
			(fill no)
			(layer "F.SilkS")
		)
		(fp_poly
			(pts
				(xy 0.21463 -0.450088) (xy 1.56337 -0.450088) (xy 1.56337 1.75006) (xy 0.21463 1.75006)
			)
			(stroke
				(width 0)
				(type default)
			)
			(fill no)
			(layer "F.CrtYd")
		)
		(fp_line
			(start 0.21463 1.75006)
			(end 0.21463 -0.450088)
			(stroke
				(width 0.1)
				(type default)
			)
			(layer "F.Fab")
		)
		(fp_line
			(start 1.56337 1.75006)
			(end 0.21463 1.75006)
			(stroke
				(width 0.1)
				(type default)
			)
			(layer "F.Fab")
		)
		(fp_line
			(start 0.21463 -0.450088)
			(end 1.56337 -0.450088)
			(stroke
				(width 0.1)
				(type default)
			)
			(layer "F.Fab")
		)
		(fp_line
			(start 1.56337 -0.450088)
			(end 1.56337 1.75006)
			(stroke
				(width 0.1)
				(type default)
			)
			(layer "F.Fab")
		)
		(fp_circle
			(center -0.4699 -0.8382)
			(end -0.4699 -0.9652)
			(stroke
				(width 0.254)
				(type default)
			)
			(fill no)
			(layer "F.Fab")
		)
		(pad "1" smd rect
			(at 0 0 270)
			(size 1.016 0.381)
			(layers "F.Cu" "F.Mask" "F.Paste")
			(net "Net_6482")
		)
		(pad "2" smd rect
			(at 0 0.649986 270)
			(size 1.016 0.381)
			(layers "F.Cu" "F.Mask" "F.Paste")
			(net "PUMP_PWM_OUT")
		)
		(pad "3" smd rect
			(at 0 1.299972 270)
			(size 1.016 0.381)
			(layers "F.Cu" "F.Mask" "F.Paste")
			(net "GND")
		)
		(pad "4" smd rect
			(at 1.778 1.299972 270)
			(size 1.016 0.381)
			(layers "F.Cu" "F.Mask" "F.Paste")
			(net "PUMP_PWM_OUT_BUF")
		)
		(pad "5" smd rect
			(at 1.778 0 270)
			(size 1.016 0.381)
			(layers "F.Cu" "F.Mask" "F.Paste")
			(net "P3V3_STBY")
		)
	)
	(footprint ""
		(layer "F.Cu")
		(at 339.2932 -29.6672 -90)
		(property "Reference" "L7F1"
			(at -4.08813 5.7658 0)
			(unlocked yes)
			(layer "F.SilkS")
			(effects
				(font
					(size 0.7874 0.5842)
					(thickness 0.1524)
				)
				(justify left)
			)
		)
		(property "Value" ""
			(at 0 0 270)
			(layer "F.Fab")
			(effects
				(font
					(size 1.27 1.27)
				)
			)
		)
		(duplicate_pad_numbers_are_jumpers no)
		(fp_line
			(start -3.4036 6.1341)
			(end -3.4036 -0.6731)
			(stroke
				(width 0.1524)
				(type default)
			)
			(layer "F.SilkS")
		)
		(fp_line
			(start -2.5654 6.1341)
			(end -3.4036 6.1341)
			(stroke
				(width 0.1524)
				(type default)
			)
			(layer "F.SilkS")
		)
		(fp_line
			(start 3.4036 6.1341)
			(end 2.5654 6.1341)
			(stroke
				(width 0.1524)
				(type default)
			)
			(layer "F.SilkS")
		)
		(fp_line
			(start -3.4036 -0.6731)
			(end -2.5654 -0.6731)
			(stroke
				(width 0.1524)
				(type default)
			)
			(layer "F.SilkS")
		)
		(fp_line
			(start 2.5654 -0.6731)
			(end 3.4036 -0.6731)
			(stroke
				(width 0.1524)
				(type default)
			)
			(layer "F.SilkS")
		)
		(fp_line
			(start 3.4036 -0.6731)
			(end 3.4036 6.1341)
			(stroke
				(width 0.1524)
				(type default)
			)
			(layer "F.SilkS")
		)
		(fp_rect
			(start 3.4036 6.1341)
			(end -3.4036 -0.6731)
			(stroke
				(width 0)
				(type default)
			)
			(fill no)
			(layer "F.CrtYd")
		)
		(fp_line
			(start -3.4036 6.1341)
			(end -3.4036 -0.6731)
			(stroke
				(width 0.1)
				(type default)
			)
			(layer "F.Fab")
		)
		(fp_line
			(start 3.4036 6.1341)
			(end -3.4036 6.1341)
			(stroke
				(width 0.1)
				(type default)
			)
			(layer "F.Fab")
		)
		(fp_line
			(start -3.4036 -0.6731)
			(end 3.4036 -0.6731)
			(stroke
				(width 0.1)
				(type default)
			)
			(layer "F.Fab")
		)
		(fp_line
			(start 3.4036 -0.6731)
			(end 3.4036 6.1341)
			(stroke
				(width 0.1)
				(type default)
			)
			(layer "F.Fab")
		)
		(pad "1" smd rect
			(at 0 0 270)
			(size 3.556 3.175)
			(layers "F.Cu" "F.Mask" "F.Paste")
			(net "VR_PVPP_ABC_PHASE")
		)
		(pad "2" smd rect
			(at 0 5.461 270)
			(size 3.556 3.175)
			(layers "F.Cu" "F.Mask" "F.Paste")
			(net "PVPP_ABC")
		)
	)
)
